# S9S_MB_2U (Grand Teton) — schematic netlist excerpt (pin names and nets, part order shuffled) for the footprints in the layout excerpt that follows; sources: Cadence DE-HDL packaged netlist, KiCad conversion of 03242023_DA0F0TMBIJ0_F0T_Motherboard_J_brd_V01_OCP.brd

C96  Q_CAP  2.2UF 6.3V 20% X6S  pkg C0402  page 105 : A = P3V3_AUX ; B = GND
R3244  Q_RES  0 5% CHIP  pkg 0402LF  page 160 : A = OCP_V3_2_RBT_ARB_OUT ; B = OCP_V3_2_RBT_ARB_IN_R
PC280_P0_4  Q_CAP  22UF 16V 20% X6S  pkg C0805  page 268 : A = SW_P12V_PVCCIN_CPU0_FLT ; B = GND

(kicad_pcb
	(version 20260206)
	(generator "pcbnew")
	(generator_version "10.0")
	(general
		(thickness 1.6)
		(legacy_teardrops no)
	)
	(paper "A4")
	(title_block
		(title "03242023_DA0F0TMBIJ0_F0T_Motherboard_J_brd_V01_OCP.brd")
		(comment 1 "Grand Teton / footprints 5755-5757 of 6105")
	)
	(layers
		(0 "F.Cu" signal "TOP")
		(4 "In1.Cu" signal "GND")
		(6 "In2.Cu" signal "IN1")
		(8 "In3.Cu" signal "GND1")
		(10 "In4.Cu" signal "IN2")
		(12 "In5.Cu" signal "GND2")
		(14 "In6.Cu" signal "IN3")
		(16 "In7.Cu" signal "GND3")
		(18 "In8.Cu" signal "VCC")
		(20 "In9.Cu" signal "VCC1")
		(22 "In10.Cu" signal "GND4")
		(24 "In11.Cu" signal "IN4")
		(26 "In12.Cu" signal "GND5")
		(28 "In13.Cu" signal "IN5")
		(30 "In14.Cu" signal "GND6")
		(32 "In15.Cu" signal "IN6")
		(34 "In16.Cu" signal "GND7")
		(2 "B.Cu" signal "BOTTOM")
		(9 "F.Adhes" user "F.Adhesive")
		(11 "B.Adhes" user "B.Adhesive")
		(13 "F.Paste" user "Package Geometry/Pastemask Top")
		(15 "B.Paste" user "Package Geometry/Pastemask Bottom")
		(5 "F.SilkS" user "Ref Des/Silkscreen Top")
		(7 "B.SilkS" user "Ref Des/Silkscreen Bottom")
		(1 "F.Mask" user "Board Geometry/Soldermask Top")
		(3 "B.Mask" user "Board Geometry/Soldermask Bottom")
		(17 "Dwgs.User" user "User.Drawings")
		(19 "Cmts.User" user "User.Comments")
		(21 "Eco1.User" user "User.Eco1")
		(23 "Eco2.User" user "User.Eco2")
		(25 "Edge.Cuts" user "Board Geometry/Outline")
		(27 "Margin" user)
		(31 "F.CrtYd" user "Package Geometry/Place Bound Top")
		(29 "B.CrtYd" user "Package Geometry/Place Bound Bottom")
		(35 "F.Fab" user "Ref Des/Assembly Top")
		(33 "B.Fab" user "Ref Des/Assembly Bottom")
	)
	(footprint ""
		(layer "B.Cu")
		(at 203.04506 -78.247748 180)
		(property "Reference" "R3244"
			(at 0 0 0)
			(layer "B.SilkS")
			(hide yes)
			(effects
				(font
					(size 1.27 1.27)
				)
				(justify mirror)
			)
		)
		(property "Value" ""
			(at 0 0 0)
			(layer "B.Fab")
			(effects
				(font
					(size 1.27 1.27)
				)
				(justify mirror)
			)
		)
		(duplicate_pad_numbers_are_jumpers no)
		(fp_line
			(start 0.7874 0.4064)
			(end 0.7874 -0.4064)
			(stroke
				(width 0.1524)
				(type default)
			)
			(layer "B.SilkS")
		)
		(fp_line
			(start 0.7874 -0.4064)
			(end -0.7874 -0.4064)
			(stroke
				(width 0.1524)
				(type default)
			)
			(layer "B.SilkS")
		)
		(fp_line
			(start -0.7874 0.4064)
			(end 0.7874 0.4064)
			(stroke
				(width 0.1524)
				(type default)
			)
			(layer "B.SilkS")
		)
		(fp_line
			(start -0.7874 -0.4064)
			(end -0.7874 0.4064)
			(stroke
				(width 0.1524)
				(type default)
			)
			(layer "B.SilkS")
		)
		(fp_line
			(start 0.67945 0.3048)
			(end 0.67945 -0.305054)
			(stroke
				(width 0.1)
				(type default)
			)
			(layer "B.Fab")
		)
		(fp_line
			(start 0.67945 -0.305054)
			(end 0.12065 -0.305054)
			(stroke
				(width 0.1)
				(type default)
			)
			(layer "B.Fab")
		)
		(fp_line
			(start 0.12065 0.3048)
			(end 0.67945 0.3048)
			(stroke
				(width 0.1)
				(type default)
			)
			(layer "B.Fab")
		)
		(fp_line
			(start 0.12065 0.2794)
			(end 0.12065 0.3048)
			(stroke
				(width 0.1)
				(type default)
			)
			(layer "B.Fab")
		)
		(fp_line
			(start 0.12065 -0.2794)
			(end -0.12065 -0.2794)
			(stroke
				(width 0.1)
				(type default)
			)
			(layer "B.Fab")
		)
		(fp_line
			(start 0.12065 -0.305054)
			(end 0.12065 -0.2794)
			(stroke
				(width 0.1)
				(type default)
			)
			(layer "B.Fab")
		)
		(fp_line
			(start -0.120396 0.3048)
			(end -0.120396 0.2794)
			(stroke
				(width 0.1)
				(type default)
			)
			(layer "B.Fab")
		)
		(fp_line
			(start -0.120396 0.2794)
			(end 0.12065 0.2794)
			(stroke
				(width 0.1)
				(type default)
			)
			(layer "B.Fab")
		)
		(fp_line
			(start -0.12065 -0.2794)
			(end -0.12065 -0.3048)
			(stroke
				(width 0.1)
				(type default)
			)
			(layer "B.Fab")
		)
		(fp_line
			(start -0.12065 -0.3048)
			(end -0.67945 -0.3048)
			(stroke
				(width 0.1)
				(type default)
			)
			(layer "B.Fab")
		)
		(fp_line
			(start -0.67945 0.3048)
			(end -0.120396 0.3048)
			(stroke
				(width 0.1)
				(type default)
			)
			(layer "B.Fab")
		)
		(fp_line
			(start -0.67945 -0.3048)
			(end -0.67945 0.3048)
			(stroke
				(width 0.1)
				(type default)
			)
			(layer "B.Fab")
		)
		(pad "1" smd circle
			(at 0.40005 0)
			(size 0 0)
			(layers "B.Cu" "B.Mask" "B.Paste")
			(net "OCP_V3_2_RBT_ARB_OUT")
		)
		(pad "2" smd circle
			(at -0.40005 0)
			(size 0 0)
			(layers "B.Cu" "B.Mask" "B.Paste")
			(net "OCP_V3_2_RBT_ARB_IN_R")
		)
	)
	(footprint ""
		(layer "B.Cu")
		(at 15.696946 -319.268856 180)
		(property "Reference" "C96"
			(at 0 0 0)
			(layer "B.SilkS")
			(hide yes)
			(effects
				(font
					(size 1.27 1.27)
				)
				(justify mirror)
			)
		)
		(property "Value" ""
			(at 0 0 0)
			(layer "B.Fab")
			(effects
				(font
					(size 1.27 1.27)
				)
				(justify mirror)
			)
		)
		(duplicate_pad_numbers_are_jumpers no)
		(fp_line
			(start 0.7874 0.4064)
			(end 0.7874 -0.4064)
			(stroke
				(width 0.1524)
				(type default)
			)
			(layer "B.SilkS")
		)
		(fp_line
			(start 0.7874 -0.4064)
			(end -0.7874 -0.4064)
			(stroke
				(width 0.1524)
				(type default)
			)
			(layer "B.SilkS")
		)
		(fp_line
			(start -0.7874 0.4064)
			(end 0.7874 0.4064)
			(stroke
				(width 0.1524)
				(type default)
			)
			(layer "B.SilkS")
		)
		(fp_line
			(start -0.7874 -0.4064)
			(end -0.7874 0.4064)
			(stroke
				(width 0.1524)
				(type default)
			)
			(layer "B.SilkS")
		)
		(fp_line
			(start 0.67945 0.3048)
			(end 0.67945 -0.305054)
			(stroke
				(width 0.1)
				(type default)
			)
			(layer "B.Fab")
		)
		(fp_line
			(start 0.67945 -0.305054)
			(end 0.12065 -0.305054)
			(stroke
				(width 0.1)
				(type default)
			)
			(layer "B.Fab")
		)
		(fp_line
			(start 0.12065 0.3048)
			(end 0.67945 0.3048)
			(stroke
				(width 0.1)
				(type default)
			)
			(layer "B.Fab")
		)
		(fp_line
			(start 0.12065 0.2794)
			(end 0.12065 0.3048)
			(stroke
				(width 0.1)
				(type default)
			)
			(layer "B.Fab")
		)
		(fp_line
			(start 0.12065 -0.2794)
			(end -0.12065 -0.2794)
			(stroke
				(width 0.1)
				(type default)
			)
			(layer "B.Fab")
		)
		(fp_line
			(start 0.12065 -0.305054)
			(end 0.12065 -0.2794)
			(stroke
				(width 0.1)
				(type default)
			)
			(layer "B.Fab")
		)
		(fp_line
			(start -0.120396 0.3048)
			(end -0.120396 0.2794)
			(stroke
				(width 0.1)
				(type default)
			)
			(layer "B.Fab")
		)
		(fp_line
			(start -0.120396 0.2794)
			(end 0.12065 0.2794)
			(stroke
				(width 0.1)
				(type default)
			)
			(layer "B.Fab")
		)
		(fp_line
			(start -0.12065 -0.2794)
			(end -0.12065 -0.3048)
			(stroke
				(width 0.1)
				(type default)
			)
			(layer "B.Fab")
		)
		(fp_line
			(start -0.12065 -0.3048)
			(end -0.67945 -0.3048)
			(stroke
				(width 0.1)
				(type default)
			)
			(layer "B.Fab")
		)
		(fp_line
			(start -0.67945 0.3048)
			(end -0.120396 0.3048)
			(stroke
				(width 0.1)
				(type default)
			)
			(layer "B.Fab")
		)
		(fp_line
			(start -0.67945 -0.3048)
			(end -0.67945 0.3048)
			(stroke
				(width 0.1)
				(type default)
			)
			(layer "B.Fab")
		)
		(pad "1" smd circle
			(at 0.40005 0)
			(size 0 0)
			(layers "B.Cu" "B.Mask" "B.Paste")
			(net "P3V3_AUX")
		)
		(pad "2" smd circle
			(at -0.40005 0)
			(size 0 0)
			(layers "B.Cu" "B.Mask" "B.Paste")
			(net "GND")
		)
	)
	(footprint ""
		(layer "B.Cu")
		(at 372.675912 -333.73568 90)
		(property "Reference" "PC280_P0_4"
			(at 0 0 90)
			(layer "B.SilkS")
			(hide yes)
			(effects
				(font
					(size 1.27 1.27)
				)
				(justify mirror)
			)
		)
		(property "Value" ""
			(at 0 0 90)
			(layer "B.Fab")
			(effects
				(font
					(size 1.27 1.27)
				)
				(justify mirror)
			)
		)
		(duplicate_pad_numbers_are_jumpers no)
		(fp_line
			(start 1.524 -0.762)
			(end -1.524 -0.762)
			(stroke
				(width 0.1524)
				(type default)
			)
			(layer "B.SilkS")
		)
		(fp_line
			(start -1.524 -0.762)
			(end -1.524 0.762)
			(stroke
				(width 0.1524)
				(type default)
			)
			(layer "B.SilkS")
		)
		(fp_line
			(start 1.524 0.762)
			(end 1.524 -0.762)
			(stroke
				(width 0.1524)
				(type default)
			)
			(layer "B.SilkS")
		)
		(fp_line
			(start -1.524 0.762)
			(end 1.524 0.762)
			(stroke
				(width 0.1524)
				(type default)
			)
			(layer "B.SilkS")
		)
		(fp_line
			(start 1.1049 -0.724916)
			(end 1.1049 0.724916)
			(stroke
				(width 0.1)
				(type default)
			)
			(layer "B.Fab")
		)
		(fp_line
			(start -1.1049 -0.724916)
			(end 1.1049 -0.724916)
			(stroke
				(width 0.1)
				(type default)
			)
			(layer "B.Fab")
		)
		(fp_line
			(start 1.1049 0.724916)
			(end -1.1049 0.724916)
			(stroke
				(width 0.1)
				(type default)
			)
			(layer "B.Fab")
		)
		(fp_line
			(start -1.1049 0.724916)
			(end -1.1049 -0.724916)
			(stroke
				(width 0.1)
				(type default)
			)
			(layer "B.Fab")
		)
		(pad "1" smd rect
			(at 0.889 0 90)
			(size 1.016 1.27)
			(layers "B.Cu" "B.Mask" "B.Paste")
			(net "SW_P12V_PVCCIN_CPU0_FLT")
		)
		(pad "2" smd rect
			(at -0.889 0 90)
			(size 1.016 1.27)
			(layers "B.Cu" "B.Mask" "B.Paste")
			(net "GND")
		)
	)
)
